(kicad_pcb
	(version 20260206)
	(generator "pcbnew")
	(generator_version "10.0")
	(general
		(thickness 1.6)
		(legacy_teardrops no)
	)
	(paper "A4")
	(title_block
		(title "pdpb — Lightning_PDPB_BRD.brd")
		(comment 1 "Lightning (Wiwynn / Facebook NVMe JBOF) / footprints 579-584 of 1140")
	)
	(layers
		(0 "F.Cu" signal "TOP")
		(4 "In1.Cu" signal "L2GND")
		(6 "In2.Cu" signal "L3")
		(8 "In3.Cu" signal "L4VCC")
		(10 "In4.Cu" signal "L5VCC")
		(12 "In5.Cu" signal "L6")
		(14 "In6.Cu" signal "L7GND")
		(2 "B.Cu" signal "BOTTOM")
		(9 "F.Adhes" user "F.Adhesive")
		(11 "B.Adhes" user "B.Adhesive")
		(13 "F.Paste" user "Package Geometry/Pastemask Top")
		(15 "B.Paste" user "Package Geometry/Pastemask Bottom")
		(5 "F.SilkS" user "Ref Des/Silkscreen Top")
		(7 "B.SilkS" user "Ref Des/Silkscreen Bottom")
		(1 "F.Mask" user "Board Geometry/Soldermask Top")
		(3 "B.Mask" user "Board Geometry/Soldermask Bottom")
		(17 "Dwgs.User" user "User.Drawings")
		(19 "Cmts.User" user "User.Comments")
		(21 "Eco1.User" user "User.Eco1")
		(23 "Eco2.User" user "User.Eco2")
		(25 "Edge.Cuts" user "Board Geometry/Outline")
		(27 "Margin" user)
		(31 "F.CrtYd" user "Package Geometry/Place Bound Top")
		(29 "B.CrtYd" user "Package Geometry/Place Bound Bottom")
		(35 "F.Fab" user "Ref Des/Assembly Top")
		(33 "B.Fab" user "Ref Des/Assembly Bottom")
	)
	(footprint ""
		(layer "F.Cu")
		(at 24.3078 -297.2816 180)
		(property "Reference" "Q15"
			(at 0 0 180)
			(layer "F.SilkS")
			(hide yes)
			(effects
				(font
					(size 1.27 1.27)
				)
			)
		)
		(property "Value" "2N7002A-7-GP"
			(at 0.127 -8.9662 180)
			(unlocked yes)
			(layer "F.Fab")
			(hide yes)
			(effects
				(font
					(size 1.016 1.016)
					(thickness 0.1524)
				)
			)
		)
		(property "Device Type" "SOT23DGS2D4H48"
			(at 0.127 -10.4902 180)
			(unlocked yes)
			(layer "F.Fab")
			(hide yes)
			(effects
				(font
					(size 1.016 1.016)
					(thickness 0.1524)
				)
			)
		)
		(duplicate_pad_numbers_are_jumpers no)
		(fp_line
			(start 1.651 1.778)
			(end 1.651 -1.778)
			(stroke
				(width 0.1524)
				(type default)
			)
			(layer "F.SilkS")
		)
		(fp_line
			(start 1.651 -1.778)
			(end -1.651 -1.778)
			(stroke
				(width 0.1524)
				(type default)
			)
			(layer "F.SilkS")
		)
		(fp_line
			(start -1.651 1.778)
			(end 1.651 1.778)
			(stroke
				(width 0.1524)
				(type default)
			)
			(layer "F.SilkS")
		)
		(fp_line
			(start -1.651 -1.778)
			(end -1.651 1.778)
			(stroke
				(width 0.1524)
				(type default)
			)
			(layer "F.SilkS")
		)
		(fp_poly
			(pts
				(xy -1.778 1.8796) (xy -1.778 -1.8796) (xy 1.778 -1.8796) (xy 1.778 1.8796)
			)
			(stroke
				(width 0)
				(type default)
			)
			(fill no)
			(layer "F.CrtYd")
		)
		(fp_poly
			(pts
				(xy -1.778 1.8796) (xy -1.778 -1.8796) (xy 1.778 -1.8796) (xy 1.778 1.8796)
			)
			(stroke
				(width 0)
				(type default)
			)
			(fill no)
			(layer "F.Fab")
		)
		(pad "D" smd custom
			(at 0 -0.9525 180)
			(size 0.1905 0.1905)
			(layers "F.Cu" "F.Mask" "F.Paste")
			(net "SW_SSD7_R")
			(options
				(clearance outline)
				(anchor circle)
			)
			(primitives
				(gr_poly
					(pts
						(arc
							(start -0.1778 0.5715)
							(mid -0.321484 0.511984)
							(end -0.381 0.3683)
						)
						(arc
							(start -0.381 -0.3683)
							(mid -0.321484 -0.511984)
							(end -0.1778 -0.5715)
						)
						(arc
							(start 0.1778 -0.5715)
							(mid 0.321484 -0.511984)
							(end 0.381 -0.3683)
						)
						(arc
							(start 0.381 0.3683)
							(mid 0.321484 0.511984)
							(end 0.1778 0.5715)
						)
					)
					(width 0)
					(fill yes)
				)
			)
		)
		(pad "G" smd custom
			(at -0.98425 0.9525 180)
			(size 0.1905 0.1905)
			(layers "F.Cu" "F.Mask" "F.Paste")
			(net "SSD7_PWREN")
			(options
				(clearance outline)
				(anchor circle)
			)
			(primitives
				(gr_poly
					(pts
						(arc
							(start -0.1778 0.5715)
							(mid -0.321484 0.511984)
							(end -0.381 0.3683)
						)
						(arc
							(start -0.381 -0.3683)
							(mid -0.321484 -0.511984)
							(end -0.1778 -0.5715)
						)
						(arc
							(start 0.1778 -0.5715)
							(mid 0.321484 -0.511984)
							(end 0.381 -0.3683)
						)
						(arc
							(start 0.381 0.3683)
							(mid 0.321484 0.511984)
							(end 0.1778 0.5715)
						)
					)
					(width 0)
					(fill yes)
				)
			)
		)
		(pad "S" smd custom
			(at 0.98425 0.9525 180)
			(size 0.1905 0.1905)
			(layers "F.Cu" "F.Mask" "F.Paste")
			(net "GND")
			(options
				(clearance outline)
				(anchor circle)
			)
			(primitives
				(gr_poly
					(pts
						(arc
							(start -0.1778 0.5715)
							(mid -0.321484 0.511984)
							(end -0.381 0.3683)
						)
						(arc
							(start -0.381 -0.3683)
							(mid -0.321484 -0.511984)
							(end -0.1778 -0.5715)
						)
						(arc
							(start 0.1778 -0.5715)
							(mid 0.321484 -0.511984)
							(end 0.381 -0.3683)
						)
						(arc
							(start 0.381 0.3683)
							(mid 0.321484 0.511984)
							(end 0.1778 0.5715)
						)
					)
					(width 0)
					(fill yes)
				)
			)
		)
	)
	(footprint ""
		(layer "F.Cu")
		(at 24.257 -462.661 -90)
		(property "Reference" "R9902"
			(at 0 0 270)
			(layer "F.SilkS")
			(hide yes)
			(effects
				(font
					(size 1.27 1.27)
				)
			)
		)
		(property "Value" "1K82R2F-1-GP"
			(at 0.064008 -3.993896 270)
			(unlocked yes)
			(layer "F.Fab")
			(hide yes)
			(effects
				(font
					(size 1.016 1.016)
					(thickness 0.1524)
				)
			)
		)
		(property "Device Type" "R402H16"
			(at 0.064008 -5.517896 270)
			(unlocked yes)
			(layer "F.Fab")
			(hide yes)
			(effects
				(font
					(size 1.016 1.016)
					(thickness 0.1524)
				)
			)
		)
		(duplicate_pad_numbers_are_jumpers no)
		(fp_line
			(start -0.508 -0.9398)
			(end -0.508 0.9398)
			(stroke
				(width 0.1524)
				(type default)
			)
			(layer "F.SilkS")
		)
		(fp_line
			(start 0.508 -0.9398)
			(end -0.508 -0.9398)
			(stroke
				(width 0.1524)
				(type default)
			)
			(layer "F.SilkS")
		)
		(fp_rect
			(start -0.508 0.9398)
			(end 0.508 -0.9398)
			(stroke
				(width 0)
				(type default)
			)
			(fill no)
			(layer "F.CrtYd")
		)
		(fp_rect
			(start -0.508 0.9398)
			(end 0.508 -0.9398)
			(stroke
				(width 0)
				(type default)
			)
			(fill no)
			(layer "F.Fab")
		)
		(pad "1" smd custom
			(at 0 -0.4445 270)
			(size 0.1397 0.1397)
			(layers "F.Cu" "F.Mask" "F.Paste")
			(net "P12V")
			(options
				(clearance outline)
				(anchor circle)
			)
			(primitives
				(gr_poly
					(pts
						(arc
							(start -0.1778 -0.2794)
							(mid -0.249642 -0.249642)
							(end -0.2794 -0.1778)
						)
						(arc
							(start -0.2794 0.1778)
							(mid -0.249642 0.249642)
							(end -0.1778 0.2794)
						)
						(arc
							(start 0.1778 0.2794)
							(mid 0.249642 0.249642)
							(end 0.2794 0.1778)
						)
						(arc
							(start 0.2794 -0.1778)
							(mid 0.249642 -0.249642)
							(end 0.1778 -0.2794)
						)
					)
					(width 0)
					(fill yes)
				)
			)
		)
		(pad "2" smd custom
			(at 0 0.4445 270)
			(size 0.1397 0.1397)
			(layers "F.Cu" "F.Mask" "F.Paste")
			(net "DRV_ACT_10")
			(options
				(clearance outline)
				(anchor circle)
			)
			(primitives
				(gr_poly
					(pts
						(arc
							(start -0.1778 -0.2794)
							(mid -0.249642 -0.249642)
							(end -0.2794 -0.1778)
						)
						(arc
							(start -0.2794 0.1778)
							(mid -0.249642 0.249642)
							(end -0.1778 0.2794)
						)
						(arc
							(start 0.1778 0.2794)
							(mid 0.249642 0.249642)
							(end 0.2794 0.1778)
						)
						(arc
							(start 0.2794 -0.1778)
							(mid 0.249642 -0.249642)
							(end 0.1778 -0.2794)
						)
					)
					(width 0)
					(fill yes)
				)
			)
		)
	)
	(footprint ""
		(layer "F.Cu")
		(at 210.947 -94.9706 -90)
		(property "Reference" "Q47"
			(at 0 0 270)
			(layer "F.SilkS")
			(hide yes)
			(effects
				(font
					(size 1.27 1.27)
				)
			)
		)
		(property "Value" "2N7002A-7-GP"
			(at 0.127 -8.9662 270)
			(unlocked yes)
			(layer "F.Fab")
			(hide yes)
			(effects
				(font
					(size 1.016 1.016)
					(thickness 0.1524)
				)
			)
		)
		(property "Device Type" "SOT23DGS2D4H48"
			(at 0.127 -10.4902 270)
			(unlocked yes)
			(layer "F.Fab")
			(hide yes)
			(effects
				(font
					(size 1.016 1.016)
					(thickness 0.1524)
				)
			)
		)
		(duplicate_pad_numbers_are_jumpers no)
		(fp_line
			(start -1.651 1.778)
			(end 1.651 1.778)
			(stroke
				(width 0.1524)
				(type default)
			)
			(layer "F.SilkS")
		)
		(fp_line
			(start 1.651 1.778)
			(end 1.651 -1.778)
			(stroke
				(width 0.1524)
				(type default)
			)
			(layer "F.SilkS")
		)
		(fp_line
			(start -1.651 -1.778)
			(end -1.651 1.778)
			(stroke
				(width 0.1524)
				(type default)
			)
			(layer "F.SilkS")
		)
		(fp_line
			(start 1.651 -1.778)
			(end -1.651 -1.778)
			(stroke
				(width 0.1524)
				(type default)
			)
			(layer "F.SilkS")
		)
		(fp_poly
			(pts
				(xy -1.778 1.8796) (xy -1.778 -1.8796) (xy 1.778 -1.8796) (xy 1.778 1.8796)
			)
			(stroke
				(width 0)
				(type default)
			)
			(fill no)
			(layer "F.CrtYd")
		)
		(fp_poly
			(pts
				(xy -1.778 1.8796) (xy -1.778 -1.8796) (xy 1.778 -1.8796) (xy 1.778 1.8796)
			)
			(stroke
				(width 0)
				(type default)
			)
			(fill no)
			(layer "F.Fab")
		)
		(pad "D" smd custom
			(at 0 -0.9525 270)
			(size 0.1905 0.1905)
			(layers "F.Cu" "F.Mask" "F.Paste")
			(net "P12V_MOST4_GATE")
			(options
				(clearance outline)
				(anchor circle)
			)
			(primitives
				(gr_poly
					(pts
						(arc
							(start -0.1778 0.5715)
							(mid -0.321484 0.511984)
							(end -0.381 0.3683)
						)
						(arc
							(start -0.381 -0.3683)
							(mid -0.321484 -0.511984)
							(end -0.1778 -0.5715)
						)
						(arc
							(start 0.1778 -0.5715)
							(mid 0.321484 -0.511984)
							(end 0.381 -0.3683)
						)
						(arc
							(start 0.381 0.3683)
							(mid 0.321484 0.511984)
							(end 0.1778 0.5715)
						)
					)
					(width 0)
					(fill yes)
				)
			)
		)
		(pad "G" smd custom
			(at -0.98425 0.9525 270)
			(size 0.1905 0.1905)
			(layers "F.Cu" "F.Mask" "F.Paste")
			(net "SSD4_PWREN_R")
			(options
				(clearance outline)
				(anchor circle)
			)
			(primitives
				(gr_poly
					(pts
						(arc
							(start -0.1778 0.5715)
							(mid -0.321484 0.511984)
							(end -0.381 0.3683)
						)
						(arc
							(start -0.381 -0.3683)
							(mid -0.321484 -0.511984)
							(end -0.1778 -0.5715)
						)
						(arc
							(start 0.1778 -0.5715)
							(mid 0.321484 -0.511984)
							(end 0.381 -0.3683)
						)
						(arc
							(start 0.381 0.3683)
							(mid 0.321484 0.511984)
							(end 0.1778 0.5715)
						)
					)
					(width 0)
					(fill yes)
				)
			)
		)
		(pad "S" smd custom
			(at 0.98425 0.9525 270)
			(size 0.1905 0.1905)
			(layers "F.Cu" "F.Mask" "F.Paste")
			(net "GND")
			(options
				(clearance outline)
				(anchor circle)
			)
			(primitives
				(gr_poly
					(pts
						(arc
							(start -0.1778 0.5715)
							(mid -0.321484 0.511984)
							(end -0.381 0.3683)
						)
						(arc
							(start -0.381 -0.3683)
							(mid -0.321484 -0.511984)
							(end -0.1778 -0.5715)
						)
						(arc
							(start 0.1778 -0.5715)
							(mid 0.321484 -0.511984)
							(end 0.381 -0.3683)
						)
						(arc
							(start 0.381 0.3683)
							(mid 0.321484 0.511984)
							(end 0.1778 0.5715)
						)
					)
					(width 0)
					(fill yes)
				)
			)
		)
	)
	(footprint ""
		(layer "F.Cu")
		(at 82.931 -308.483 -90)
		(property "Reference" "PR9062"
			(at 0 0 270)
			(layer "F.SilkS")
			(hide yes)
			(effects
				(font
					(size 1.27 1.27)
				)
			)
		)
		(property "Value" "1K4R2F-1-GP"
			(at 0.064008 -3.993896 270)
			(unlocked yes)
			(layer "F.Fab")
			(hide yes)
			(effects
				(font
					(size 1.016 1.016)
					(thickness 0.1524)
				)
			)
		)
		(property "Device Type" "R402H16"
			(at 0.064008 -5.517896 270)
			(unlocked yes)
			(layer "F.Fab")
			(hide yes)
			(effects
				(font
					(size 1.016 1.016)
					(thickness 0.1524)
				)
			)
		)
		(duplicate_pad_numbers_are_jumpers no)
		(fp_line
			(start -0.508 -0.9398)
			(end -0.508 0.9398)
			(stroke
				(width 0.1524)
				(type default)
			)
			(layer "F.SilkS")
		)
		(fp_line
			(start 0.508 -0.9398)
			(end -0.508 -0.9398)
			(stroke
				(width 0.1524)
				(type default)
			)
			(layer "F.SilkS")
		)
		(fp_rect
			(start -0.508 0.9398)
			(end 0.508 -0.9398)
			(stroke
				(width 0)
				(type default)
			)
			(fill no)
			(layer "F.CrtYd")
		)
		(fp_rect
			(start -0.508 0.9398)
			(end 0.508 -0.9398)
			(stroke
				(width 0)
				(type default)
			)
			(fill no)
			(layer "F.Fab")
		)
		(pad "1" smd custom
			(at 0 -0.4445 270)
			(size 0.1397 0.1397)
			(layers "F.Cu" "F.Mask" "F.Paste")
			(net "CLK_BUF_EU2_HIBW_BYPM_LOBW#")
			(options
				(clearance outline)
				(anchor circle)
			)
			(primitives
				(gr_poly
					(pts
						(arc
							(start -0.1778 -0.2794)
							(mid -0.249642 -0.249642)
							(end -0.2794 -0.1778)
						)
						(arc
							(start -0.2794 0.1778)
							(mid -0.249642 0.249642)
							(end -0.1778 0.2794)
						)
						(arc
							(start 0.1778 0.2794)
							(mid 0.249642 0.249642)
							(end 0.2794 0.1778)
						)
						(arc
							(start 0.2794 -0.1778)
							(mid 0.249642 -0.249642)
							(end 0.1778 -0.2794)
						)
					)
					(width 0)
					(fill yes)
				)
			)
		)
		(pad "2" smd custom
			(at 0 0.4445 270)
			(size 0.1397 0.1397)
			(layers "F.Cu" "F.Mask" "F.Paste")
			(net "GND")
			(options
				(clearance outline)
				(anchor circle)
			)
			(primitives
				(gr_poly
					(pts
						(arc
							(start -0.1778 -0.2794)
							(mid -0.249642 -0.249642)
							(end -0.2794 -0.1778)
						)
						(arc
							(start -0.2794 0.1778)
							(mid -0.249642 0.249642)
							(end -0.1778 0.2794)
						)
						(arc
							(start 0.1778 0.2794)
							(mid 0.249642 0.249642)
							(end 0.2794 0.1778)
						)
						(arc
							(start 0.2794 -0.1778)
							(mid 0.249642 -0.249642)
							(end 0.1778 -0.2794)
						)
					)
					(width 0)
					(fill yes)
				)
			)
		)
	)
	(footprint ""
		(layer "F.Cu")
		(at 94.488 -109.474 180)
		(property "Reference" "C8873"
			(at 0 0 180)
			(layer "F.SilkS")
			(hide yes)
			(effects
				(font
					(size 1.27 1.27)
				)
			)
		)
		(property "Value" "SCD1U16V2KX-3GP"
			(at 1.1811 -2.7051 180)
			(unlocked yes)
			(layer "F.Fab")
			(hide yes)
			(effects
				(font
					(size 1.016 1.016)
					(thickness 0.1524)
				)
			)
		)
		(property "Device Type" "C402H22"
			(at 1.1811 -4.2291 180)
			(unlocked yes)
			(layer "F.Fab")
			(hide yes)
			(effects
				(font
					(size 1.016 1.016)
					(thickness 0.1524)
				)
			)
		)
		(duplicate_pad_numbers_are_jumpers no)
		(fp_rect
			(start -0.4318 0.9525)
			(end 0.4318 -0.9525)
			(stroke
				(width 0)
				(type default)
			)
			(fill no)
			(layer "F.CrtYd")
		)
		(fp_rect
			(start -0.4318 0.9525)
			(end 0.4318 -0.9525)
			(stroke
				(width 0)
				(type default)
			)
			(fill no)
			(layer "F.Fab")
		)
		(pad "1" smd custom
			(at 0 -0.4445 180)
			(size 0.1524 0.1524)
			(layers "F.Cu" "F.Mask" "F.Paste")
			(net "VDD_IO_4")
			(options
				(clearance outline)
				(anchor circle)
			)
			(primitives
				(gr_poly
					(pts
						(arc
							(start 0.3048 -0.2032)
							(mid 0.275042 -0.275042)
							(end 0.2032 -0.3048)
						)
						(arc
							(start -0.2032 -0.3048)
							(mid -0.275042 -0.275042)
							(end -0.3048 -0.2032)
						)
						(arc
							(start -0.3048 0.2032)
							(mid -0.275042 0.275042)
							(end -0.2032 0.3048)
						)
						(arc
							(start 0.2032 0.3048)
							(mid 0.275042 0.275042)
							(end 0.3048 0.2032)
						)
					)
					(width 0)
					(fill yes)
				)
			)
		)
		(pad "2" smd custom
			(at 0 0.4445 180)
			(size 0.1524 0.1524)
			(layers "F.Cu" "F.Mask" "F.Paste")
			(net "GND")
			(options
				(clearance outline)
				(anchor circle)
			)
			(primitives
				(gr_poly
					(pts
						(arc
							(start 0.3048 -0.2032)
							(mid 0.275042 -0.275042)
							(end 0.2032 -0.3048)
						)
						(arc
							(start -0.2032 -0.3048)
							(mid -0.275042 -0.275042)
							(end -0.3048 -0.2032)
						)
						(arc
							(start -0.3048 0.2032)
							(mid -0.275042 0.275042)
							(end -0.2032 0.3048)
						)
						(arc
							(start 0.2032 0.3048)
							(mid 0.275042 0.275042)
							(end 0.3048 0.2032)
						)
					)
					(width 0)
					(fill yes)
				)
			)
		)
	)
	(footprint ""
		(layer "F.Cu")
		(at 107.442 -309.88 -90)
		(property "Reference" "R9494"
			(at 0 0 270)
			(layer "F.SilkS")
			(hide yes)
			(effects
				(font
					(size 1.27 1.27)
				)
			)
		)
		(property "Value" "10R2F-L-GP"
			(at 0.064008 -3.993896 270)
			(unlocked yes)
			(layer "F.Fab")
			(hide yes)
			(effects
				(font
					(size 1.016 1.016)
					(thickness 0.1524)
				)
			)
		)
		(property "Device Type" "R402H14"
			(at 0.064008 -5.517896 270)
			(unlocked yes)
			(layer "F.Fab")
			(hide yes)
			(effects
				(font
					(size 1.016 1.016)
					(thickness 0.1524)
				)
			)
		)
		(duplicate_pad_numbers_are_jumpers no)
		(fp_line
			(start -0.508 -0.9398)
			(end -0.508 0.9398)
			(stroke
				(width 0.1524)
				(type default)
			)
			(layer "F.SilkS")
		)
		(fp_line
			(start 0.508 -0.9398)
			(end -0.508 -0.9398)
			(stroke
				(width 0.1524)
				(type default)
			)
			(layer "F.SilkS")
		)
		(fp_rect
			(start -0.508 0.9398)
			(end 0.508 -0.9398)
			(stroke
				(width 0)
				(type default)
			)
			(fill no)
			(layer "F.CrtYd")
		)
		(fp_rect
			(start -0.508 0.9398)
			(end 0.508 -0.9398)
			(stroke
				(width 0)
				(type default)
			)
			(fill no)
			(layer "F.Fab")
		)
		(pad "1" smd custom
			(at 0 -0.4445 270)
			(size 0.1397 0.1397)
			(layers "F.Cu" "F.Mask" "F.Paste")
			(net "SSD1_CLK0_OE_N")
			(options
				(clearance outline)
				(anchor circle)
			)
			(primitives
				(gr_poly
					(pts
						(arc
							(start -0.1778 -0.2794)
							(mid -0.249642 -0.249642)
							(end -0.2794 -0.1778)
						)
						(arc
							(start -0.2794 0.1778)
							(mid -0.249642 0.249642)
							(end -0.1778 0.2794)
						)
						(arc
							(start 0.1778 0.2794)
							(mid 0.249642 0.249642)
							(end 0.2794 0.1778)
						)
						(arc
							(start 0.2794 -0.1778)
							(mid 0.249642 -0.249642)
							(end 0.1778 -0.2794)
						)
					)
					(width 0)
					(fill yes)
				)
			)
		)
		(pad "2" smd custom
			(at 0 0.4445 270)
			(size 0.1397 0.1397)
			(layers "F.Cu" "F.Mask" "F.Paste")
			(net "SSD1_CLK0_OE_R_N")
			(options
				(clearance outline)
				(anchor circle)
			)
			(primitives
				(gr_poly
					(pts
						(arc
							(start -0.1778 -0.2794)
							(mid -0.249642 -0.249642)
							(end -0.2794 -0.1778)
						)
						(arc
							(start -0.2794 0.1778)
							(mid -0.249642 0.249642)
							(end -0.1778 0.2794)
						)
						(arc
							(start 0.1778 0.2794)
							(mid 0.249642 0.249642)
							(end 0.2794 0.1778)
						)
						(arc
							(start 0.2794 -0.1778)
							(mid 0.249642 -0.249642)
							(end 0.1778 -0.2794)
						)
					)
					(width 0)
					(fill yes)
				)
			)
		)
	)
)
